FILE_TYPE = CONNECTIVITY;
{Allegro Design Entry HDL 17.2-2016 S081 (4005846) 1/11/2022}
"PAGE_NUMBER" = 142;
0"NC";
1"P3V3_STBY\g";
2"BIOS_DEBUG_MODE";
3"LED_BIOS_DBG_MODE_N";
4"LED_BIOS_DBG_MODE";
5"LED_BIOS_DBG_MODE_R";
6"P3V3_STBY\g";
7"GND\g";
%"Q_LED"
"1","(-4650,1575)","0","pure_quanta","I79";
;
LOCATION"D9"
$SEC"1"
CDS_SEC"1"
MANUF_PN"19-213/GVC-AMNB/3T"
MATERIAL"IC"
PART_NUMBER"BEGR0278Z00"
COLOR"LED_GREEN"
PACK_TYPE"SMLF"
CDS_LIB"pure_quanta"
NEEDS_NO_SIZE"TRUE";
"A"
$PN"A"5;
"C"
$PN"C"4;
%"MOSFET_N_GSD"
"1","(-3550,1300)","2","pure_quanta","I80";
;
LOCATION"Q29"
$SEC"1"
CDS_SEC"1"
PART_TYPE"SMLF"
MATERIAL"IC"
VALUE"NX138BK"
PART_NUMBER"BAM01380023"
NEEDS_NO_SIZE"TRUE"
CDS_LMAN_SYM_OUTLINE"-100,100,100,-100"
CDS_LIB"pure_quanta";
"DRAIN"
$PN"D"4;
"SOURCE"
$PN"S"7;
"GATE"
$PN"G"3;
%"MOSFET_N_GSD"
"1","(-2525,925)","2","pure_quanta","I81";
;
LOCATION"Q30"
$SEC"1"
CDS_SEC"1"
PART_TYPE"SMLF"
MATERIAL"IC"
VALUE"NX138BK"
PART_NUMBER"BAM01380023"
CDS_LIB"pure_quanta"
CDS_LMAN_SYM_OUTLINE"-100,100,100,-100"
NEEDS_NO_SIZE"TRUE";
"DRAIN"
$PN"D"3;
"SOURCE"
$PN"S"7;
"GATE"
$PN"G"2;
%"Q_RES"
"1","(-5550,1575)","0","pure_quanta","I82";
;
LOCATION"R1444"
$SEC"1"
CDS_SEC"1"
WATTAGE"1/16W"
MATERIAL"CHIP"
TOLERANCE"1%"
VALUE"200"
PART_NUMBER"CS12002FB06"
PACK_TYPE"0402LF"
CDS_LIB"pure_quanta";
"B"
$PN"2"5;
"A"
$PN"1"6;
%"UNIVERSAL_POWER"
"1","(-5925,1825)","0","pure_quanta_power","I83";
;
HDL_POWER"P3V3_STBY"
BOM_COST"OCP3.0 "
CDS_LIB"pure_quanta_power";
"A"6;
%"UNIVERSAL_GND"
"1","(-2550,625)","0","pure_quanta_power","I85";
;
HDL_POWER"GND"
BOM_COST"MISC."
CDS_LIB"pure_quanta_power";
"A"7;
%"UNIVERSAL_POWER"
"1","(-2550,1725)","0","pure_quanta_power","I86";
;
HDL_POWER"P3V3_STBY"
CDS_LIB"pure_quanta_power";
"A"1;
%"Q_RES"
"2","(-2550,1500)","0","pure_quanta","I87";
;
LOCATION"R1507"
$SEC"1"
CDS_SEC"1"
WATTAGE"1/16W"
MATERIAL"CHIP"
TOLERANCE"5%"
VALUE"1K"
PACK_TYPE"0402LF"
CDS_LIB"pure_quanta"
PART_NUMBER"TMP_QCS21002JB34";
"A"
$PN"1"1;
"B"
$PN"2"3;
END.
